(kicad_pcb
	(version 20260206)
	(generator "pcbnew")
	(generator_version "10.0")
	(general
		(thickness 1.6)
		(legacy_teardrops no)
	)
	(paper "A4")
	(title_block
		(title "Wiwynn_Tioga_Pass_MB.brd")
		(comment 1 "Tioga Pass / footprints 1509-1515 of 4770")
	)
	(layers
		(0 "F.Cu" signal "TOP")
		(4 "In1.Cu" signal "L2GND")
		(6 "In2.Cu" signal "L3")
		(8 "In3.Cu" signal "L4GND")
		(10 "In4.Cu" signal "L5")
		(12 "In5.Cu" signal "L6GND")
		(14 "In6.Cu" signal "L7VCC")
		(16 "In7.Cu" signal "L8VCC")
		(18 "In8.Cu" signal "L9GND")
		(20 "In9.Cu" signal "L10")
		(22 "In10.Cu" signal "L11GND")
		(24 "In11.Cu" signal "L12")
		(26 "In12.Cu" signal "L13GND")
		(2 "B.Cu" signal "BOTTOM")
		(9 "F.Adhes" user "F.Adhesive")
		(11 "B.Adhes" user "B.Adhesive")
		(13 "F.Paste" user "Package Geometry/Pastemask Top")
		(15 "B.Paste" user "Package Geometry/Pastemask Bottom")
		(5 "F.SilkS" user "Ref Des/Silkscreen Top")
		(7 "B.SilkS" user "Ref Des/Silkscreen Bottom")
		(1 "F.Mask" user "Board Geometry/Soldermask Top")
		(3 "B.Mask" user "Board Geometry/Soldermask Bottom")
		(17 "Dwgs.User" user "User.Drawings")
		(19 "Cmts.User" user "User.Comments")
		(21 "Eco1.User" user "User.Eco1")
		(23 "Eco2.User" user "User.Eco2")
		(25 "Edge.Cuts" user "Board Geometry/Outline")
		(27 "Margin" user)
		(31 "F.CrtYd" user "Package Geometry/Place Bound Top")
		(29 "B.CrtYd" user "Package Geometry/Place Bound Bottom")
		(35 "F.Fab" user "Ref Des/Assembly Top")
		(33 "B.Fab" user "Ref Des/Assembly Bottom")
	)
	(footprint ""
		(layer "F.Cu")
		(at 184.133998 -2.705608 -90)
		(property "Reference" "EU4G3"
			(at 3.086608 -1.617472 90)
			(unlocked yes)
			(layer "F.SilkS")
			(effects
				(font
					(size 0.7874 0.5842)
					(thickness 0.1524)
				)
				(justify left)
			)
		)
		(property "Value" ""
			(at 0 0 270)
			(layer "F.Fab")
			(effects
				(font
					(size 1.27 1.27)
				)
			)
		)
		(duplicate_pad_numbers_are_jumpers no)
		(fp_circle
			(center -0.835152 -0.417322)
			(end -0.835152 -0.544068)
			(stroke
				(width 0.254)
				(type default)
			)
			(fill no)
			(layer "F.SilkS")
		)
		(fp_poly
			(pts
				(xy -0.064516 -1.0922) (xy -0.064516 -0.3302) (xy 0.697484 -1.0922)
			)
			(stroke
				(width 0)
				(type default)
			)
			(fill yes)
			(layer "F.SilkS")
		)
		(fp_rect
			(start 0.597408 2.295398)
			(end 2.273808 -0.295402)
			(stroke
				(width 0)
				(type default)
			)
			(fill yes)
			(layer "F.Paste")
		)
		(fp_rect
			(start -0.064516 2.500122)
			(end 2.935478 -0.500126)
			(stroke
				(width 0)
				(type default)
			)
			(fill no)
			(layer "F.CrtYd")
		)
		(fp_line
			(start -0.064516 2.500122)
			(end -0.064516 -0.500126)
			(stroke
				(width 0.1)
				(type default)
			)
			(layer "F.Fab")
		)
		(fp_line
			(start 2.935478 2.500122)
			(end -0.064516 2.500122)
			(stroke
				(width 0.1)
				(type default)
			)
			(layer "F.Fab")
		)
		(fp_line
			(start -0.064516 -0.500126)
			(end 2.935478 -0.500126)
			(stroke
				(width 0.1)
				(type default)
			)
			(layer "F.Fab")
		)
		(fp_line
			(start 2.935478 -0.500126)
			(end 2.935478 2.500122)
			(stroke
				(width 0.1)
				(type default)
			)
			(layer "F.Fab")
		)
		(fp_circle
			(center -0.835152 -0.417322)
			(end -0.835152 -0.544068)
			(stroke
				(width 0.254)
				(type default)
			)
			(fill no)
			(layer "F.Fab")
		)
		(pad "1" smd rect
			(at 0 0 270)
			(size 0.6858 0.3048)
			(layers "F.Cu" "F.Mask" "F.Paste")
			(net "VR_PVTT_ABC_VREF")
		)
		(pad "2" smd rect
			(at 0 0.500126 270)
			(size 0.6858 0.3048)
			(layers "F.Cu" "F.Mask" "F.Paste")
			(net "VR_PVTT_ABC_BIAS")
		)
		(pad "3" smd rect
			(at 0 0.999998 270)
			(size 0.6858 0.3048)
			(layers "F.Cu" "F.Mask" "F.Paste")
			(net "GND")
		)
		(pad "4" smd rect
			(at 0 1.500124 270)
			(size 0.6858 0.3048)
			(layers "F.Cu" "F.Mask" "F.Paste")
			(net "VSENSE_PVDDQ_ABC_VTT")
		)
		(pad "5" smd rect
			(at 0 1.999996 270)
			(size 0.6858 0.3048)
			(layers "F.Cu" "F.Mask" "F.Paste")
			(net "PWRGD_PVTT_ABC_CPU0_R")
		)
		(pad "6" smd rect
			(at 2.871216 1.999996 270)
			(size 0.6858 0.3048)
			(layers "F.Cu" "F.Mask" "F.Paste")
			(net "VR_PVTT_ABC_SNS")
		)
		(pad "7" smd rect
			(at 2.871216 1.500124 270)
			(size 0.6858 0.3048)
			(layers "F.Cu" "F.Mask" "F.Paste")
			(net "FM_PVTT_ABC_EN_R")
		)
		(pad "8" smd rect
			(at 2.871216 0.999998 270)
			(size 0.6858 0.3048)
			(layers "F.Cu" "F.Mask" "F.Paste")
			(net "GND")
		)
		(pad "9" smd rect
			(at 2.871216 0.500126 270)
			(size 0.6858 0.3048)
			(layers "F.Cu" "F.Mask" "F.Paste")
			(net "PVTT_ABC")
		)
		(pad "10" smd rect
			(at 2.871216 0 270)
			(size 0.6858 0.3048)
			(layers "F.Cu" "F.Mask" "F.Paste")
			(net "PVDDQ_ABC")
		)
		(pad "11" smd rect
			(at 1.435608 0.999998 270)
			(size 1.6764 2.5908)
			(layers "F.Cu" "F.Mask" "F.Paste")
			(net "GND")
		)
	)
	(footprint ""
		(layer "F.Cu")
		(at 340.429088 -10.34161 90)
		(property "Reference" "RT34"
			(at 0 0 90)
			(layer "F.SilkS")
			(hide yes)
			(effects
				(font
					(size 1.27 1.27)
				)
			)
		)
		(property "Value" "*"
			(at -0.0254 -2.6289 90)
			(unlocked yes)
			(layer "F.Fab")
			(hide yes)
			(effects
				(font
					(size 1.27 1.016)
					(thickness 0.1524)
				)
			)
		)
		(property "Device Type" "1R3F-GP_RCL_GP-1R3F-GP,64.1R00A"
			(at -0.0254 -4.1529 90)
			(unlocked yes)
			(layer "F.Fab")
			(hide yes)
			(effects
				(font
					(size 1.27 1.016)
					(thickness 0.1524)
				)
			)
		)
		(duplicate_pad_numbers_are_jumpers no)
		(fp_line
			(start 0.2032 0)
			(end 0.4826 0)
			(stroke
				(width 0.2032)
				(type default)
			)
			(layer "F.SilkS")
		)
		(fp_line
			(start -0.4826 0)
			(end -0.2032 0)
			(stroke
				(width 0.2032)
				(type default)
			)
			(layer "F.SilkS")
		)
		(fp_rect
			(start -0.5842 1.3335)
			(end 0.5842 -1.3335)
			(stroke
				(width 0)
				(type default)
			)
			(fill no)
			(layer "F.CrtYd")
		)
		(fp_rect
			(start -0.5842 1.3335)
			(end 0.5842 -1.3335)
			(stroke
				(width 0)
				(type default)
			)
			(fill no)
			(layer "F.Fab")
		)
		(pad "1" smd custom
			(at 0 -0.762 90)
			(size 0.2159 0.2159)
			(layers "F.Cu" "F.Mask" "F.Paste")
			(net "VR_PVDDQ_ABC_PH1_SW_RC")
			(options
				(clearance outline)
				(anchor circle)
			)
			(primitives
				(gr_poly
					(pts
						(arc
							(start -0.3302 -0.4318)
							(mid -0.402042 -0.402042)
							(end -0.4318 -0.3302)
						)
						(arc
							(start -0.4318 0.3302)
							(mid -0.402042 0.402042)
							(end -0.3302 0.4318)
						)
						(arc
							(start 0.3302 0.4318)
							(mid 0.402042 0.402042)
							(end 0.4318 0.3302)
						)
						(arc
							(start 0.4318 -0.3302)
							(mid 0.402042 -0.402042)
							(end 0.3302 -0.4318)
						)
					)
					(width 0)
					(fill yes)
				)
			)
		)
		(pad "2" smd custom
			(at 0 0.762 90)
			(size 0.2159 0.2159)
			(layers "F.Cu" "F.Mask" "F.Paste")
			(net "GND")
			(options
				(clearance outline)
				(anchor circle)
			)
			(primitives
				(gr_poly
					(pts
						(arc
							(start -0.3302 -0.4318)
							(mid -0.402042 -0.402042)
							(end -0.4318 -0.3302)
						)
						(arc
							(start -0.4318 0.3302)
							(mid -0.402042 0.402042)
							(end -0.3302 0.4318)
						)
						(arc
							(start 0.3302 0.4318)
							(mid 0.402042 0.402042)
							(end 0.4318 0.3302)
						)
						(arc
							(start 0.4318 -0.3302)
							(mid 0.402042 -0.402042)
							(end 0.3302 -0.4318)
						)
					)
					(width 0)
					(fill yes)
				)
			)
		)
	)
	(footprint ""
		(layer "F.Cu")
		(at 166.649146 -146.302222 180)
		(property "Reference" "C4A13"
			(at 0 0 180)
			(layer "F.SilkS")
			(hide yes)
			(effects
				(font
					(size 1.27 1.27)
				)
			)
		)
		(property "Value" ""
			(at 0 0 180)
			(layer "F.Fab")
			(effects
				(font
					(size 1.27 1.27)
				)
			)
		)
		(duplicate_pad_numbers_are_jumpers no)
		(fp_rect
			(start -0.7239 1.9939)
			(end 0.7239 -0.2159)
			(stroke
				(width 0)
				(type default)
			)
			(fill no)
			(layer "F.CrtYd")
		)
		(fp_line
			(start 0.7239 1.9939)
			(end 0.7239 -0.2159)
			(stroke
				(width 0.1)
				(type default)
			)
			(layer "F.Fab")
		)
		(fp_line
			(start 0.7239 -0.2159)
			(end -0.7239 -0.2159)
			(stroke
				(width 0.1)
				(type default)
			)
			(layer "F.Fab")
		)
		(fp_line
			(start -0.7239 1.9939)
			(end 0.7239 1.9939)
			(stroke
				(width 0.1)
				(type default)
			)
			(layer "F.Fab")
		)
		(fp_line
			(start -0.7239 -0.2159)
			(end -0.7239 1.9939)
			(stroke
				(width 0.1)
				(type default)
			)
			(layer "F.Fab")
		)
		(pad "1" smd rect
			(at 0 0 180)
			(size 1.27 1.016)
			(layers "F.Cu" "F.Mask" "F.Paste")
			(net "PVTT_KLM")
		)
		(pad "2" smd rect
			(at 0 1.778 180)
			(size 1.27 1.016)
			(layers "F.Cu" "F.Mask" "F.Paste")
			(net "GND")
		)
		(zone
			(layer "F.Cu")
			(hatch none 0.5)
			(connect_pads
				(clearance 0)
			)
			(min_thickness 0.25)
			(keepout
				(tracks not_allowed)
				(vias allowed)
				(pads allowed)
				(copperpour not_allowed)
				(footprints allowed)
			)
			(placement
				(enabled no)
				(sheetname "")
			)
			(fill
				(thermal_gap 0.5)
				(thermal_bridge_width 0.5)
				(island_removal_mode 0)
			)
			(polygon
				(pts
					(xy 167.284146 -147.572222) (xy 166.014146 -147.572222) (xy 166.014146 -146.810222) (xy 167.284146 -146.810222)
				)
			)
		)
	)
	(footprint ""
		(layer "F.Cu")
		(at 13.8938 -33.909 90)
		(property "Reference" "C1F5"
			(at 0 0 90)
			(layer "F.SilkS")
			(hide yes)
			(effects
				(font
					(size 1.27 1.27)
				)
			)
		)
		(property "Value" ""
			(at 0 0 90)
			(layer "F.Fab")
			(effects
				(font
					(size 1.27 1.27)
				)
			)
		)
		(duplicate_pad_numbers_are_jumpers no)
		(fp_rect
			(start -0.3048 -0.1016)
			(end 0.3048 0.9906)
			(stroke
				(width 0)
				(type default)
			)
			(fill no)
			(layer "F.CrtYd")
		)
		(fp_line
			(start 0.3048 -0.1016)
			(end -0.3048 -0.1016)
			(stroke
				(width 0.1)
				(type default)
			)
			(layer "F.Fab")
		)
		(fp_line
			(start -0.3048 -0.1016)
			(end -0.3048 0.9906)
			(stroke
				(width 0.1)
				(type default)
			)
			(layer "F.Fab")
		)
		(fp_line
			(start 0.3048 0.9906)
			(end 0.3048 -0.1016)
			(stroke
				(width 0.1)
				(type default)
			)
			(layer "F.Fab")
		)
		(fp_line
			(start -0.3048 0.9906)
			(end 0.3048 0.9906)
			(stroke
				(width 0.1)
				(type default)
			)
			(layer "F.Fab")
		)
		(pad "1" smd rect
			(at 0 0 90)
			(size 0.508 0.508)
			(layers "F.Cu" "F.Mask" "F.Paste")
			(net "P3E_CPU1_PE3_MP_C_TXP<6>")
		)
		(pad "2" smd rect
			(at 0 0.889 90)
			(size 0.508 0.508)
			(layers "F.Cu" "F.Mask" "F.Paste")
			(net "P3E_CPU1_PE3_MP_TXP<6>")
		)
		(zone
			(layer "F.Cu")
			(hatch none 0.5)
			(connect_pads
				(clearance 0)
			)
			(min_thickness 0.25)
			(keepout
				(tracks not_allowed)
				(vias allowed)
				(pads allowed)
				(copperpour not_allowed)
				(footprints allowed)
			)
			(placement
				(enabled no)
				(sheetname "")
			)
			(fill
				(thermal_gap 0.5)
				(thermal_bridge_width 0.5)
				(island_removal_mode 0)
			)
			(polygon
				(pts
					(xy 14.1478 -33.655) (xy 14.5288 -33.655) (xy 14.5288 -34.163) (xy 14.1478 -34.163)
				)
			)
		)
		(zone
			(layer "F.Cu")
			(hatch none 0.5)
			(connect_pads
				(clearance 0)
			)
			(min_thickness 0.25)
			(keepout
				(tracks allowed)
				(vias not_allowed)
				(pads allowed)
				(copperpour not_allowed)
				(footprints allowed)
			)
			(placement
				(enabled no)
				(sheetname "")
			)
			(fill
				(thermal_gap 0.5)
				(thermal_bridge_width 0.5)
				(island_removal_mode 0)
			)
			(polygon
				(pts
					(xy 14.1478 -33.655) (xy 14.5288 -33.655) (xy 14.5288 -34.163) (xy 14.1478 -34.163)
				)
			)
		)
	)
	(footprint ""
		(layer "F.Cu")
		(at 398.145 -77.7875 180)
		(property "Reference" "R8E7"
			(at 0 0 180)
			(layer "F.SilkS")
			(hide yes)
			(effects
				(font
					(size 1.27 1.27)
				)
			)
		)
		(property "Value" ""
			(at 0 0 180)
			(layer "F.Fab")
			(effects
				(font
					(size 1.27 1.27)
				)
			)
		)
		(duplicate_pad_numbers_are_jumpers no)
		(fp_poly
			(pts
				(xy -0.2794 -0.1016) (xy 0.2794 -0.1016) (xy 0.2794 0.9906) (xy -0.2794 0.9906)
			)
			(stroke
				(width 0)
				(type default)
			)
			(fill no)
			(layer "F.CrtYd")
		)
		(fp_line
			(start 0.2794 0.9906)
			(end 0.2794 -0.1016)
			(stroke
				(width 0.1)
				(type default)
			)
			(layer "F.Fab")
		)
		(fp_line
			(start 0.2794 -0.1016)
			(end -0.2794 -0.1016)
			(stroke
				(width 0.1)
				(type default)
			)
			(layer "F.Fab")
		)
		(fp_line
			(start -0.2794 0.9906)
			(end 0.2794 0.9906)
			(stroke
				(width 0.1)
				(type default)
			)
			(layer "F.Fab")
		)
		(fp_line
			(start -0.2794 -0.1016)
			(end -0.2794 0.9906)
			(stroke
				(width 0.1)
				(type default)
			)
			(layer "F.Fab")
		)
		(pad "1" smd rect
			(at 0 0 180)
			(size 0.508 0.508)
			(layers "F.Cu" "F.Mask" "F.Paste")
			(net "PWRGD_P12V_HSC_DLY_R")
		)
		(pad "2" smd rect
			(at 0 0.889 180)
			(size 0.508 0.508)
			(layers "F.Cu" "F.Mask" "F.Paste")
			(net "PWRGD_P12V_HSC_DLY")
		)
		(zone
			(layer "F.Cu")
			(hatch none 0.5)
			(connect_pads
				(clearance 0)
			)
			(min_thickness 0.25)
			(keepout
				(tracks not_allowed)
				(vias allowed)
				(pads allowed)
				(copperpour not_allowed)
				(footprints allowed)
			)
			(placement
				(enabled no)
				(sheetname "")
			)
			(fill
				(thermal_gap 0.5)
				(thermal_bridge_width 0.5)
				(island_removal_mode 0)
			)
			(polygon
				(pts
					(xy 398.399 -78.4225) (xy 397.891 -78.4225) (xy 397.891 -78.0415) (xy 398.399 -78.0415)
				)
			)
		)
		(zone
			(layer "F.Cu")
			(hatch none 0.5)
			(connect_pads
				(clearance 0)
			)
			(min_thickness 0.25)
			(keepout
				(tracks allowed)
				(vias not_allowed)
				(pads allowed)
				(copperpour not_allowed)
				(footprints allowed)
			)
			(placement
				(enabled no)
				(sheetname "")
			)
			(fill
				(thermal_gap 0.5)
				(thermal_bridge_width 0.5)
				(island_removal_mode 0)
			)
			(polygon
				(pts
					(xy 398.399 -78.0415) (xy 397.891 -78.0415) (xy 397.891 -78.4225) (xy 398.399 -78.4225)
				)
			)
		)
	)
	(footprint ""
		(layer "F.Cu")
		(at 411.0355 -110.617 -90)
		(property "Reference" "R8C9"
			(at 0 0 270)
			(layer "F.SilkS")
			(hide yes)
			(effects
				(font
					(size 1.27 1.27)
				)
			)
		)
		(property "Value" ""
			(at 0 0 270)
			(layer "F.Fab")
			(effects
				(font
					(size 1.27 1.27)
				)
			)
		)
		(duplicate_pad_numbers_are_jumpers no)
		(fp_poly
			(pts
				(xy -0.2794 -0.1016) (xy 0.2794 -0.1016) (xy 0.2794 0.9906) (xy -0.2794 0.9906)
			)
			(stroke
				(width 0)
				(type default)
			)
			(fill no)
			(layer "F.CrtYd")
		)
		(fp_line
			(start -0.2794 0.9906)
			(end 0.2794 0.9906)
			(stroke
				(width 0.1)
				(type default)
			)
			(layer "F.Fab")
		)
		(fp_line
			(start 0.2794 0.9906)
			(end 0.2794 -0.1016)
			(stroke
				(width 0.1)
				(type default)
			)
			(layer "F.Fab")
		)
		(fp_line
			(start -0.2794 -0.1016)
			(end -0.2794 0.9906)
			(stroke
				(width 0.1)
				(type default)
			)
			(layer "F.Fab")
		)
		(fp_line
			(start 0.2794 -0.1016)
			(end -0.2794 -0.1016)
			(stroke
				(width 0.1)
				(type default)
			)
			(layer "F.Fab")
		)
		(pad "1" smd rect
			(at 0 0 270)
			(size 0.508 0.508)
			(layers "F.Cu" "F.Mask" "F.Paste")
			(net "P3V3_STBY")
		)
		(pad "2" smd rect
			(at 0 0.889 270)
			(size 0.508 0.508)
			(layers "F.Cu" "F.Mask" "F.Paste")
			(net "IRQ_SML0_ALERT_N")
		)
		(zone
			(layer "F.Cu")
			(hatch none 0.5)
			(connect_pads
				(clearance 0)
			)
			(min_thickness 0.25)
			(keepout
				(tracks not_allowed)
				(vias allowed)
				(pads allowed)
				(copperpour not_allowed)
				(footprints allowed)
			)
			(placement
				(enabled no)
				(sheetname "")
			)
			(fill
				(thermal_gap 0.5)
				(thermal_bridge_width 0.5)
				(island_removal_mode 0)
			)
			(polygon
				(pts
					(xy 410.4005 -110.871) (xy 410.4005 -110.363) (xy 410.7815 -110.363) (xy 410.7815 -110.871)
				)
			)
		)
		(zone
			(layer "F.Cu")
			(hatch none 0.5)
			(connect_pads
				(clearance 0)
			)
			(min_thickness 0.25)
			(keepout
				(tracks allowed)
				(vias not_allowed)
				(pads allowed)
				(copperpour not_allowed)
				(footprints allowed)
			)
			(placement
				(enabled no)
				(sheetname "")
			)
			(fill
				(thermal_gap 0.5)
				(thermal_bridge_width 0.5)
				(island_removal_mode 0)
			)
			(polygon
				(pts
					(xy 410.7815 -110.871) (xy 410.7815 -110.363) (xy 410.4005 -110.363) (xy 410.4005 -110.871)
				)
			)
		)
	)
	(footprint ""
		(layer "F.Cu")
		(at 96.94164 -77.636116)
		(property "Reference" "C2D22"
			(at 0 0 0)
			(layer "F.SilkS")
			(hide yes)
			(effects
				(font
					(size 1.27 1.27)
				)
			)
		)
		(property "Value" ""
			(at 0 0 0)
			(layer "F.Fab")
			(effects
				(font
					(size 1.27 1.27)
				)
			)
		)
		(duplicate_pad_numbers_are_jumpers no)
		(fp_poly
			(pts
				(xy -0.4953 -0.2032) (xy 0.4953 -0.2032) (xy 0.4953 1.6002) (xy -0.4953 1.6002)
			)
			(stroke
				(width 0)
				(type default)
			)
			(fill no)
			(layer "F.CrtYd")
		)
		(fp_line
			(start -0.4953 -0.2032)
			(end 0.4953 -0.2032)
			(stroke
				(width 0.1)
				(type default)
			)
			(layer "F.Fab")
		)
		(fp_line
			(start -0.4953 1.6002)
			(end -0.4953 -0.2032)
			(stroke
				(width 0.1)
				(type default)
			)
			(layer "F.Fab")
		)
		(fp_line
			(start 0.4953 -0.2032)
			(end 0.4953 1.6002)
			(stroke
				(width 0.1)
				(type default)
			)
			(layer "F.Fab")
		)
		(fp_line
			(start 0.4953 1.6002)
			(end -0.4953 1.6002)
			(stroke
				(width 0.1)
				(type default)
			)
			(layer "F.Fab")
		)
		(pad "1" smd rect
			(at 0 0)
			(size 0.762 0.889)
			(layers "F.Cu" "F.Mask" "F.Paste")
			(net "PVCCIN_CPU1")
		)
		(pad "2" smd rect
			(at 0 1.397)
			(size 0.762 0.889)
			(layers "F.Cu" "F.Mask" "F.Paste")
			(net "GND")
		)
		(zone
			(layer "F.Cu")
			(hatch none 0.5)
			(connect_pads
				(clearance 0)
			)
			(min_thickness 0.25)
			(keepout
				(tracks not_allowed)
				(vias allowed)
				(pads allowed)
				(copperpour not_allowed)
				(footprints allowed)
			)
			(placement
				(enabled no)
				(sheetname "")
			)
			(fill
				(thermal_gap 0.5)
				(thermal_bridge_width 0.5)
				(island_removal_mode 0)
			)
			(polygon
				(pts
					(xy 96.56064 -77.191616) (xy 97.32264 -77.191616) (xy 97.32264 -76.683616) (xy 96.56064 -76.683616)
				)
			)
		)
	)
)
